(kicad_pcb
	(version 20241229)
	(generator "pcbnew")
	(generator_version "9.0")
	(general
		(thickness 1.6642)
		(legacy_teardrops no)
	)
	(paper "A3")
	(title_block
		(title "PolarFire SoM")
		(date "2025-07-22")
		(rev "1.1.4")
		(company "Antmicro Ltd")
		(comment 1 "www.antmicro.com")
		(comment 9 "footprints 426-430 of 470")
	)
	(layers
		(0 "F.Cu" mixed)
		(4 "In1.Cu" power)
		(6 "In2.Cu" signal)
		(8 "In3.Cu" power)
		(10 "In4.Cu" signal)
		(12 "In5.Cu" power)
		(14 "In6.Cu" power)
		(16 "In7.Cu" signal)
		(18 "In8.Cu" power)
		(20 "In9.Cu" signal)
		(22 "In10.Cu" power)
		(24 "In11.Cu" signal)
		(26 "In12.Cu" signal)
		(2 "B.Cu" mixed)
		(9 "F.Adhes" user "F.Adhesive")
		(11 "B.Adhes" user "B.Adhesive")
		(13 "F.Paste" user)
		(15 "B.Paste" user)
		(5 "F.SilkS" user "F.Silkscreen")
		(7 "B.SilkS" user "B.Silkscreen")
		(1 "F.Mask" user)
		(3 "B.Mask" user)
		(17 "Dwgs.User" user "User.Drawings")
		(19 "Cmts.User" user "User.Comments")
		(21 "Eco1.User" user "User.Eco1")
		(23 "Eco2.User" user "User.Eco2")
		(25 "Edge.Cuts" user)
		(27 "Margin" user)
		(31 "F.CrtYd" user "F.Courtyard")
		(29 "B.CrtYd" user "B.Courtyard")
		(35 "F.Fab" user)
		(33 "B.Fab" user)
	)
	(footprint "antmicro-footprints:R_0402_1005Metric"
		(layer "B.Cu")
		(at 187.85 120.85 -90)
		(descr "Resistor SMD 0402")
		(tags "resistor SMD 0402")
		(property "Reference" "R42"
			(at -4.875 -0.2 90)
			(layer "B.SilkS")
			(effects
				(font
					(size 0.7 0.7)
					(thickness 0.15)
				)
				(justify left bottom mirror)
			)
		)
		(property "Value" "R_1k_0402"
			(at -1.011843 -1.772047 90)
			(layer "B.Fab")
			(hide yes)
			(effects
				(font
					(size 0.7 0.7)
					(thickness 0.15)
				)
				(justify left bottom mirror)
			)
		)
		(property "Datasheet" "https://www.bourns.com/docs/product-datasheets/cr.pdf"
			(at 0 0 270)
			(layer "F.Fab")
			(hide yes)
			(effects
				(font
					(size 1.27 1.27)
					(thickness 0.15)
				)
			)
		)
		(property "Description" "SMD Chip Resistor, 1 kohm, ± 1%, 63 mW, 0402 [1005 Metric], Thick Film, General Purpose"
			(at 0 0 270)
			(layer "F.Fab")
			(hide yes)
			(effects
				(font
					(size 1.27 1.27)
					(thickness 0.15)
				)
			)
		)
		(property "Author" "Antmicro"
			(at 67 308.7 0)
			(layer "B.Fab")
			(hide yes)
			(effects
				(font
					(size 1 1)
					(thickness 0.15)
				)
				(justify mirror)
			)
		)
		(property "License" "Apache-2.0"
			(at 67 308.7 0)
			(layer "B.Fab")
			(hide yes)
			(effects
				(font
					(size 1 1)
					(thickness 0.15)
				)
				(justify mirror)
			)
		)
		(property "MPN" "CR0402-FX-1001GLF"
			(at 67 308.7 0)
			(layer "B.Fab")
			(hide yes)
			(effects
				(font
					(size 1 1)
					(thickness 0.15)
				)
				(justify mirror)
			)
		)
		(property "Manufacturer" "Bourns"
			(at 67 308.7 0)
			(layer "B.Fab")
			(hide yes)
			(effects
				(font
					(size 1 1)
					(thickness 0.15)
				)
				(justify mirror)
			)
		)
		(property "Public" ""
			(at 67 308.7 0)
			(layer "B.Fab")
			(hide yes)
			(effects
				(font
					(size 1 1)
					(thickness 0.15)
				)
				(justify mirror)
			)
		)
		(property "Tolerance" "1%"
			(at 67 308.7 0)
			(layer "B.Fab")
			(hide yes)
			(effects
				(font
					(size 1 1)
					(thickness 0.15)
				)
				(justify mirror)
			)
		)
		(property "Val" "1k"
			(at 67 308.7 0)
			(layer "B.Fab")
			(hide yes)
			(effects
				(font
					(size 1 1)
					(thickness 0.15)
				)
				(justify mirror)
			)
		)
		(sheetname "/FPGA Config/")
		(sheetfile "fpga-config.kicad_sch")
		(attr smd)
		(fp_rect
			(start -0.925 0.47)
			(end 0.925 -0.47)
			(stroke
				(width 0.05)
				(type default)
			)
			(fill no)
			(layer "B.CrtYd")
		)
		(fp_rect
			(start -0.5 0.25)
			(end 0.5 -0.25)
			(stroke
				(width 0.15)
				(type solid)
			)
			(fill no)
			(layer "B.Fab")
		)
		(fp_text user "Author: Antmicro"
			(at -0.95 -4.169 90)
			(layer "B.Fab")
			(effects
				(font
					(size 0.7 0.7)
					(thickness 0.15)
				)
				(justify left bottom mirror)
			)
		)
		(fp_text user "License: Apache-2.0"
			(at -0.95 -5.169 90)
			(layer "B.Fab")
			(effects
				(font
					(size 0.7 0.7)
					(thickness 0.15)
				)
				(justify left bottom mirror)
			)
		)
		(fp_text user "${REFERENCE}"
			(at -0.95 -3.168 90)
			(layer "B.Fab")
			(effects
				(font
					(size 0.7 0.7)
					(thickness 0.15)
				)
				(justify left bottom mirror)
			)
		)
		(pad "1" smd roundrect
			(at -0.48 0 270)
			(size 0.59 0.64)
			(layers "B.Cu" "B.Mask" "B.Paste")
			(roundrect_rratio 0.25)
			(net 655 "/FPGA Config/DEVRST_N")
			(pintype "passive")
		)
		(pad "2" smd roundrect
			(at 0.48 0 270)
			(size 0.59 0.64)
			(layers "B.Cu" "B.Mask" "B.Paste")
			(roundrect_rratio 0.25)
			(net 50 "+3V3")
			(pintype "passive")
		)
	)
	(footprint "antmicro-footprints:R_0402_1005Metric"
		(layer "B.Cu")
		(at 210.1925 131.347)
		(descr "Resistor SMD 0402")
		(tags "resistor SMD 0402")
		(property "Reference" "R32"
			(at -0.8425 0.628 180)
			(layer "B.SilkS")
			(effects
				(font
					(size 0.7 0.7)
					(thickness 0.15)
				)
				(justify left bottom mirror)
			)
		)
		(property "Value" "R_49k9_0402"
			(at -1.011843 -1.772047 180)
			(layer "B.Fab")
			(hide yes)
			(effects
				(font
					(size 0.7 0.7)
					(thickness 0.15)
				)
				(justify left bottom mirror)
			)
		)
		(property "Datasheet" "https://www.bourns.com/docs/product-datasheets/cr.pdf"
			(at 0 0 0)
			(layer "F.Fab")
			(hide yes)
			(effects
				(font
					(size 1.27 1.27)
					(thickness 0.15)
				)
			)
		)
		(property "Description" "SMD Chip Resistor, 49.9 kohm, ± 1%, 63 mW, 0402 [1005 Metric], Thick Film, General Purpose"
			(at 0 0 0)
			(layer "F.Fab")
			(hide yes)
			(effects
				(font
					(size 1.27 1.27)
					(thickness 0.15)
				)
			)
		)
		(property "Author" "Antmicro"
			(at 0 0 0)
			(layer "B.Fab")
			(hide yes)
			(effects
				(font
					(size 1 1)
					(thickness 0.15)
				)
				(justify mirror)
			)
		)
		(property "License" "Apache-2.0"
			(at 0 0 0)
			(layer "B.Fab")
			(hide yes)
			(effects
				(font
					(size 1 1)
					(thickness 0.15)
				)
				(justify mirror)
			)
		)
		(property "MPN" "CR0402-FX-4992GLF"
			(at 0 0 0)
			(layer "B.Fab")
			(hide yes)
			(effects
				(font
					(size 1 1)
					(thickness 0.15)
				)
				(justify mirror)
			)
		)
		(property "Manufacturer" "Bourns"
			(at 0 0 0)
			(layer "B.Fab")
			(hide yes)
			(effects
				(font
					(size 1 1)
					(thickness 0.15)
				)
				(justify mirror)
			)
		)
		(property "Public" ""
			(at 0 0 0)
			(layer "B.Fab")
			(hide yes)
			(effects
				(font
					(size 1 1)
					(thickness 0.15)
				)
				(justify mirror)
			)
		)
		(property "Tolerance" "1%"
			(at 0 0 0)
			(layer "B.Fab")
			(hide yes)
			(effects
				(font
					(size 1 1)
					(thickness 0.15)
				)
				(justify mirror)
			)
		)
		(property "Val" "49k9"
			(at 0 0 0)
			(layer "B.Fab")
			(hide yes)
			(effects
				(font
					(size 1 1)
					(thickness 0.15)
				)
				(justify mirror)
			)
		)
		(sheetname "/Memory/")
		(sheetfile "memory.kicad_sch")
		(attr smd)
		(fp_rect
			(start -0.925 0.47)
			(end 0.925 -0.47)
			(stroke
				(width 0.05)
				(type default)
			)
			(fill no)
			(layer "B.CrtYd")
		)
		(fp_rect
			(start -0.5 0.25)
			(end 0.5 -0.25)
			(stroke
				(width 0.15)
				(type solid)
			)
			(fill no)
			(layer "B.Fab")
		)
		(fp_text user "License: Apache-2.0"
			(at -0.95 -5.169 180)
			(layer "B.Fab")
			(effects
				(font
					(size 0.7 0.7)
					(thickness 0.15)
				)
				(justify left bottom mirror)
			)
		)
		(fp_text user "${REFERENCE}"
			(at -0.95 -3.168 180)
			(layer "B.Fab")
			(effects
				(font
					(size 0.7 0.7)
					(thickness 0.15)
				)
				(justify left bottom mirror)
			)
		)
		(fp_text user "Author: Antmicro"
			(at -0.95 -4.169 180)
			(layer "B.Fab")
			(effects
				(font
					(size 0.7 0.7)
					(thickness 0.15)
				)
				(justify left bottom mirror)
			)
		)
		(pad "1" smd roundrect
			(at -0.48 0)
			(size 0.59 0.64)
			(layers "B.Cu" "B.Mask" "B.Paste")
			(roundrect_rratio 0.25)
			(net 249 "/FPGA MSSIO/EMMC.DAT6")
			(pintype "passive")
		)
		(pad "2" smd roundrect
			(at 0.48 0)
			(size 0.59 0.64)
			(layers "B.Cu" "B.Mask" "B.Paste")
			(roundrect_rratio 0.25)
			(net 137 "SD_VDD")
			(pintype "passive")
		)
	)
	(footprint "antmicro-footprints:R_0402_1005Metric"
		(layer "B.Cu")
		(at 184.262625 146.299364 -45)
		(descr "Resistor SMD 0402")
		(tags "resistor SMD 0402")
		(property "Reference" "R84"
			(at 3.046224 -1.645253 315)
			(layer "B.SilkS")
			(effects
				(font
					(size 0.7 0.7)
					(thickness 0.15)
				)
				(justify left bottom mirror)
			)
		)
		(property "Value" "R_0R_0402"
			(at -1.011843 -1.772046 135)
			(layer "B.Fab")
			(hide yes)
			(effects
				(font
					(size 0.7 0.7)
					(thickness 0.15)
				)
				(justify left bottom mirror)
			)
		)
		(property "Datasheet" "https://industrial.panasonic.com/cdbs/www-data/pdf/RDA0000/AOA0000C301.pdf"
			(at 0 0 315)
			(layer "F.Fab")
			(hide yes)
			(effects
				(font
					(size 1.27 1.27)
					(thickness 0.15)
				)
			)
		)
		(property "Description" "SMD Chip Resistor, Jumper, 0 ohm, 100 mW, 0402 [1005 Metric], Thick Film, General Purpose"
			(at 0 0 315)
			(layer "F.Fab")
			(hide yes)
			(effects
				(font
					(size 1.27 1.27)
					(thickness 0.15)
				)
			)
		)
		(property "Author" "Antmicro"
			(at -49.479999 173.143443 0)
			(layer "B.Fab")
			(hide yes)
			(effects
				(font
					(size 1 1)
					(thickness 0.15)
				)
				(justify mirror)
			)
		)
		(property "Current" "1A"
			(at -49.479999 173.143443 0)
			(layer "B.Fab")
			(hide yes)
			(effects
				(font
					(size 1 1)
					(thickness 0.15)
				)
				(justify mirror)
			)
		)
		(property "License" "Apache-2.0"
			(at -49.479999 173.143443 0)
			(layer "B.Fab")
			(hide yes)
			(effects
				(font
					(size 1 1)
					(thickness 0.15)
				)
				(justify mirror)
			)
		)
		(property "MPN" "ERJ2GE0R00X"
			(at -49.479999 173.143443 0)
			(layer "B.Fab")
			(hide yes)
			(effects
				(font
					(size 1 1)
					(thickness 0.15)
				)
				(justify mirror)
			)
		)
		(property "Manufacturer" "Panasonic"
			(at -49.479999 173.143443 0)
			(layer "B.Fab")
			(hide yes)
			(effects
				(font
					(size 1 1)
					(thickness 0.15)
				)
				(justify mirror)
			)
		)
		(property "Public" ""
			(at -49.479999 173.143443 0)
			(layer "B.Fab")
			(hide yes)
			(effects
				(font
					(size 1 1)
					(thickness 0.15)
				)
				(justify mirror)
			)
		)
		(property "Tolerance" "~"
			(at -49.479999 173.143443 0)
			(layer "B.Fab")
			(hide yes)
			(effects
				(font
					(size 1 1)
					(thickness 0.15)
				)
				(justify mirror)
			)
		)
		(property "Val" "0R"
			(at -49.479999 173.143443 0)
			(layer "B.Fab")
			(hide yes)
			(effects
				(font
					(size 1 1)
					(thickness 0.15)
				)
				(justify mirror)
			)
		)
		(sheetname "/Supply/")
		(sheetfile "supply.kicad_sch")
		(attr smd)
		(fp_poly
			(pts
				(xy -0.925 0.47) (xy 0.925 0.47) (xy 0.925 -0.47) (xy -0.925 -0.47)
			)
			(stroke
				(width 0.05)
				(type default)
			)
			(fill no)
			(layer "B.CrtYd")
		)
		(fp_poly
			(pts
				(xy -0.5 0.25) (xy 0.5 0.25) (xy 0.5 -0.25) (xy -0.5 -0.25)
			)
			(stroke
				(width 0.15)
				(type solid)
			)
			(fill no)
			(layer "B.Fab")
		)
		(fp_text user "License: Apache-2.0"
			(at -0.949999 -5.169 135)
			(layer "B.Fab")
			(effects
				(font
					(size 0.7 0.7)
					(thickness 0.15)
				)
				(justify left bottom mirror)
			)
		)
		(fp_text user "Author: Antmicro"
			(at -0.95 -4.169 135)
			(layer "B.Fab")
			(effects
				(font
					(size 0.7 0.7)
					(thickness 0.15)
				)
				(justify left bottom mirror)
			)
		)
		(fp_text user "${REFERENCE}"
			(at -0.95 -3.168 135)
			(layer "B.Fab")
			(effects
				(font
					(size 0.7 0.7)
					(thickness 0.15)
				)
				(justify left bottom mirror)
			)
		)
		(pad "1" smd roundrect
			(at -0.48 0 315)
			(size 0.59 0.64)
			(layers "B.Cu" "B.Mask" "B.Paste")
			(roundrect_rratio 0.25)
			(net 634 "Net-(U7-OUT5)")
			(pintype "passive")
		)
		(pad "2" smd roundrect
			(at 0.48 0 315)
			(size 0.59 0.64)
			(layers "B.Cu" "B.Mask" "B.Paste")
			(roundrect_rratio 0.25)
			(net 237 "1V8_CL")
			(pintype "passive")
		)
	)
	(footprint "antmicro-footprints:C_0402_1005Metric"
		(layer "B.Cu")
		(at 175.25 136.6 90)
		(descr "Capacitor SMD 0402")
		(tags "capacitor SMD 0402")
		(property "Reference" "C168"
			(at 1.425 1.375 270)
			(layer "B.SilkS")
			(effects
				(font
					(size 0.7 0.7)
					(thickness 0.15)
				)
				(justify left bottom mirror)
			)
		)
		(property "Value" "C_1u_0402"
			(at -1.022927 -2.155213 270)
			(layer "B.Fab")
			(hide yes)
			(effects
				(font
					(size 0.7 0.7)
					(thickness 0.15)
				)
				(justify left bottom mirror)
			)
		)
		(property "Datasheet" "https://product.tdk.com/en/search/capacitor/ceramic/mlcc/info?part_no=C1005X6S1A105K050BC"
			(at 0 0 90)
			(layer "F.Fab")
			(hide yes)
			(effects
				(font
					(size 1.27 1.27)
					(thickness 0.15)
				)
			)
		)
		(property "Description" "SMD Multilayer Ceramic Capacitor, 1 µF, 10 V, 0402 [1005 Metric], ± 10%, X6S, C"
			(at 0 0 90)
			(layer "F.Fab")
			(hide yes)
			(effects
				(font
					(size 1.27 1.27)
					(thickness 0.15)
				)
			)
		)
		(property "Author" "Antmicro"
			(at 311.85 -38.65 0)
			(layer "B.Fab")
			(hide yes)
			(effects
				(font
					(size 1 1)
					(thickness 0.15)
				)
				(justify mirror)
			)
		)
		(property "Dielectric" "X5R"
			(at 311.85 -38.65 0)
			(layer "B.Fab")
			(hide yes)
			(effects
				(font
					(size 1 1)
					(thickness 0.15)
				)
				(justify mirror)
			)
		)
		(property "License" "Apache-2.0"
			(at 311.85 -38.65 0)
			(layer "B.Fab")
			(hide yes)
			(effects
				(font
					(size 1 1)
					(thickness 0.15)
				)
				(justify mirror)
			)
		)
		(property "MPN" "C1005X6S1A105K050BC"
			(at 311.85 -38.65 0)
			(layer "B.Fab")
			(hide yes)
			(effects
				(font
					(size 1 1)
					(thickness 0.15)
				)
				(justify mirror)
			)
		)
		(property "Manufacturer" "TDK"
			(at 311.85 -38.65 0)
			(layer "B.Fab")
			(hide yes)
			(effects
				(font
					(size 1 1)
					(thickness 0.15)
				)
				(justify mirror)
			)
		)
		(property "Public" ""
			(at 311.85 -38.65 0)
			(layer "B.Fab")
			(hide yes)
			(effects
				(font
					(size 1 1)
					(thickness 0.15)
				)
				(justify mirror)
			)
		)
		(property "Val" "1u"
			(at 311.85 -38.65 0)
			(layer "B.Fab")
			(hide yes)
			(effects
				(font
					(size 1 1)
					(thickness 0.15)
				)
				(justify mirror)
			)
		)
		(property "Voltage" "16V"
			(at 311.85 -38.65 0)
			(layer "B.Fab")
			(hide yes)
			(effects
				(font
					(size 1 1)
					(thickness 0.15)
				)
				(justify mirror)
			)
		)
		(sheetname "/LPDDR4/")
		(sheetfile "lpddr.kicad_sch")
		(attr smd)
		(fp_rect
			(start -0.925 0.47)
			(end 0.925 -0.47)
			(stroke
				(width 0.05)
				(type default)
			)
			(fill no)
			(layer "B.CrtYd")
		)
		(fp_line
			(start 0.504 -0.248)
			(end -0.494 -0.248)
			(stroke
				(width 0.15)
				(type solid)
			)
			(layer "B.Fab")
		)
		(fp_line
			(start -0.494 -0.248)
			(end -0.494 0.25)
			(stroke
				(width 0.15)
				(type solid)
			)
			(layer "B.Fab")
		)
		(fp_line
			(start 0.504 0.25)
			(end 0.504 -0.248)
			(stroke
				(width 0.15)
				(type solid)
			)
			(layer "B.Fab")
		)
		(fp_line
			(start -0.494 0.25)
			(end 0.504 0.25)
			(stroke
				(width 0.15)
				(type solid)
			)
			(layer "B.Fab")
		)
		(fp_text user "Author: Antmicro"
			(at -0.939 -3.399 270)
			(layer "B.Fab")
			(effects
				(font
					(size 0.7 0.7)
					(thickness 0.15)
				)
				(justify left bottom mirror)
			)
		)
		(fp_text user "License: Apache-2.0"
			(at -0.939 -5.799 270)
			(layer "B.Fab")
			(effects
				(font
					(size 0.7 0.7)
					(thickness 0.15)
				)
				(justify left bottom mirror)
			)
		)
		(fp_text user "${REFERENCE}"
			(at -0.939 -4.599 270)
			(layer "B.Fab")
			(effects
				(font
					(size 0.7 0.7)
					(thickness 0.15)
				)
				(justify left bottom mirror)
			)
		)
		(pad "1" smd roundrect
			(at -0.48 0 90)
			(size 0.59 0.64)
			(layers "B.Cu" "B.Mask" "B.Paste")
			(roundrect_rratio 0.25)
			(net 417 "GND")
			(pintype "passive")
		)
		(pad "2" smd roundrect
			(at 0.48 0 90)
			(size 0.59 0.64)
			(layers "B.Cu" "B.Mask" "B.Paste")
			(roundrect_rratio 0.25)
			(net 2 "+1V1")
			(pintype "passive")
		)
	)
	(footprint "antmicro-footprints:C_0402_1005Metric"
		(layer "B.Cu")
		(at 193.776 129.1)
		(descr "Capacitor SMD 0402")
		(tags "capacitor SMD 0402")
		(property "Reference" "C13"
			(at -2.976 0.45 0)
			(layer "B.SilkS")
			(effects
				(font
					(size 0.7 0.7)
					(thickness 0.15)
				)
				(justify right bottom mirror)
			)
		)
		(property "Value" "C_10n_0402"
			(at -1.022927 -2.155213 0)
			(layer "B.Fab")
			(hide yes)
			(effects
				(font
					(size 0.7 0.7)
					(thickness 0.15)
				)
				(justify right bottom mirror)
			)
		)
		(property "Datasheet" "https://www.murata.com/products/productdetail?partno=GRM155R71H103KA88%23"
			(at 0 0 0)
			(layer "F.Fab")
			(hide yes)
			(effects
				(font
					(size 1.27 1.27)
					(thickness 0.15)
				)
			)
		)
		(property "Description" "SMD Multilayer Ceramic Capacitor, 10000 pF, 50 V, 0402 [1005 Metric], ± 10%, X7R, GRM Series"
			(at 0 0 0)
			(layer "F.Fab")
			(hide yes)
			(effects
				(font
					(size 1.27 1.27)
					(thickness 0.15)
				)
			)
		)
		(property "Author" "Antmicro"
			(at 0 0 0)
			(layer "B.Fab")
			(hide yes)
			(effects
				(font
					(size 1 1)
					(thickness 0.15)
				)
				(justify mirror)
			)
		)
		(property "Dielectric" "X7R"
			(at 0 0 0)
			(layer "B.Fab")
			(hide yes)
			(effects
				(font
					(size 1 1)
					(thickness 0.15)
				)
				(justify mirror)
			)
		)
		(property "License" "Apache-2.0"
			(at 0 0 0)
			(layer "B.Fab")
			(hide yes)
			(effects
				(font
					(size 1 1)
					(thickness 0.15)
				)
				(justify mirror)
			)
		)
		(property "MPN" "GRM155R71H103KA88D"
			(at 0 0 0)
			(layer "B.Fab")
			(hide yes)
			(effects
				(font
					(size 1 1)
					(thickness 0.15)
				)
				(justify mirror)
			)
		)
		(property "Manufacturer" "Murata"
			(at 0 0 0)
			(layer "B.Fab")
			(hide yes)
			(effects
				(font
					(size 1 1)
					(thickness 0.15)
				)
				(justify mirror)
			)
		)
		(property "Public" ""
			(at 0 0 0)
			(layer "B.Fab")
			(hide yes)
			(effects
				(font
					(size 1 1)
					(thickness 0.15)
				)
				(justify mirror)
			)
		)
		(property "Val" "10n"
			(at 0 0 0)
			(layer "B.Fab")
			(hide yes)
			(effects
				(font
					(size 1 1)
					(thickness 0.15)
				)
				(justify mirror)
			)
		)
		(property "Voltage" "50V"
			(at 0 0 0)
			(layer "B.Fab")
			(hide yes)
			(effects
				(font
					(size 1 1)
					(thickness 0.15)
				)
				(justify mirror)
			)
		)
		(sheetname "/FPGA Supply/")
		(sheetfile "fpga-supply.kicad_sch")
		(attr smd)
		(fp_rect
			(start -0.925 0.47)
			(end 0.925 -0.47)
			(stroke
				(width 0.05)
				(type default)
			)
			(fill no)
			(layer "B.CrtYd")
		)
		(fp_line
			(start -0.494 -0.248)
			(end -0.494 0.25)
			(stroke
				(width 0.15)
				(type solid)
			)
			(layer "B.Fab")
		)
		(fp_line
			(start -0.494 0.25)
			(end 0.504 0.25)
			(stroke
				(width 0.15)
				(type solid)
			)
			(layer "B.Fab")
		)
		(fp_line
			(start 0.504 -0.248)
			(end -0.494 -0.248)
			(stroke
				(width 0.15)
				(type solid)
			)
			(layer "B.Fab")
		)
		(fp_line
			(start 0.504 0.25)
			(end 0.504 -0.248)
			(stroke
				(width 0.15)
				(type solid)
			)
			(layer "B.Fab")
		)
		(fp_text user "${REFERENCE}"
			(at -0.939 -4.599 180)
			(layer "B.Fab")
			(effects
				(font
					(size 0.7 0.7)
					(thickness 0.15)
				)
				(justify left bottom mirror)
			)
		)
		(fp_text user "Author: Antmicro"
			(at -0.939 -3.399 180)
			(layer "B.Fab")
			(effects
				(font
					(size 0.7 0.7)
					(thickness 0.15)
				)
				(justify left bottom mirror)
			)
		)
		(fp_text user "License: Apache-2.0"
			(at -0.939 -5.799 180)
			(layer "B.Fab")
			(effects
				(font
					(size 0.7 0.7)
					(thickness 0.15)
				)
				(justify left bottom mirror)
			)
		)
		(pad "1" smd roundrect
			(at -0.48 0)
			(size 0.59 0.64)
			(layers "B.Cu" "B.Mask" "B.Paste")
			(roundrect_rratio 0.25)
			(net 417 "GND")
			(pintype "passive")
		)
		(pad "2" smd roundrect
			(at 0.48 0)
			(size 0.59 0.64)
			(layers "B.Cu" "B.Mask" "B.Paste")
			(roundrect_rratio 0.25)
			(net 2 "+1V1")
			(pintype "passive")
		)
	)
)
